(kicad_pcb
	(version 20260206)
	(generator "pcbnew")
	(generator_version "10.0")
	(general
		(thickness 1.6)
		(legacy_teardrops no)
	)
	(paper "A4")
	(title_block
		(title "Bryce Canyon_R.DPB_16317-1_OCP.brd")
		(comment 1 "Bryce Canyon / footprints 540-546 of 2099")
	)
	(layers
		(0 "F.Cu" signal "TOP")
		(4 "In1.Cu" signal "L2GND")
		(6 "In2.Cu" signal "L3")
		(8 "In3.Cu" signal "L4VCC")
		(10 "In4.Cu" signal "L5VCC")
		(12 "In5.Cu" signal "L6")
		(14 "In6.Cu" signal "L7GND")
		(2 "B.Cu" signal "BOTTOM")
		(9 "F.Adhes" user "F.Adhesive")
		(11 "B.Adhes" user "B.Adhesive")
		(13 "F.Paste" user "Package Geometry/Pastemask Top")
		(15 "B.Paste" user "Package Geometry/Pastemask Bottom")
		(5 "F.SilkS" user "Ref Des/Silkscreen Top")
		(7 "B.SilkS" user "Ref Des/Silkscreen Bottom")
		(1 "F.Mask" user "Board Geometry/Soldermask Top")
		(3 "B.Mask" user "Board Geometry/Soldermask Bottom")
		(17 "Dwgs.User" user "User.Drawings")
		(19 "Cmts.User" user "User.Comments")
		(21 "Eco1.User" user "User.Eco1")
		(23 "Eco2.User" user "User.Eco2")
		(25 "Edge.Cuts" user "Board Geometry/Outline")
		(27 "Margin" user)
		(31 "F.CrtYd" user "Package Geometry/Place Bound Top")
		(29 "B.CrtYd" user "Package Geometry/Place Bound Bottom")
		(35 "F.Fab" user "Ref Des/Assembly Top")
		(33 "B.Fab" user "Ref Des/Assembly Bottom")
	)
	(footprint ""
		(layer "F.Cu")
		(at 15.24 -18.161 180)
		(property "Reference" "R638"
			(at 0 0 180)
			(layer "F.SilkS")
			(hide yes)
			(effects
				(font
					(size 1.27 1.27)
				)
			)
		)
		(property "Value" "200KR2F-L-GP"
			(at 0.064008 -3.993896 180)
			(unlocked yes)
			(layer "F.Fab")
			(hide yes)
			(effects
				(font
					(size 1.016 1.016)
					(thickness 0.1524)
				)
			)
		)
		(property "Device Type" "R402H16"
			(at 0.064008 -5.517896 180)
			(unlocked yes)
			(layer "F.Fab")
			(hide yes)
			(effects
				(font
					(size 1.016 1.016)
					(thickness 0.1524)
				)
			)
		)
		(duplicate_pad_numbers_are_jumpers no)
		(fp_line
			(start 0.508 -0.9398)
			(end -0.508 -0.9398)
			(stroke
				(width 0.1524)
				(type default)
			)
			(layer "F.SilkS")
		)
		(fp_line
			(start -0.508 -0.9398)
			(end -0.508 0.9398)
			(stroke
				(width 0.1524)
				(type default)
			)
			(layer "F.SilkS")
		)
		(fp_rect
			(start -0.508 0.9398)
			(end 0.508 -0.9398)
			(stroke
				(width 0)
				(type default)
			)
			(fill no)
			(layer "F.CrtYd")
		)
		(fp_rect
			(start -0.508 0.9398)
			(end 0.508 -0.9398)
			(stroke
				(width 0)
				(type default)
			)
			(fill no)
			(layer "F.Fab")
		)
		(pad "1" smd custom
			(at 0 -0.4445 180)
			(size 0.1397 0.1397)
			(layers "F.Cu" "F.Mask" "F.Paste")
			(net "SW_HDD_R24")
			(options
				(clearance outline)
				(anchor circle)
			)
			(primitives
				(gr_poly
					(pts
						(arc
							(start -0.1778 -0.2794)
							(mid -0.249642 -0.249642)
							(end -0.2794 -0.1778)
						)
						(arc
							(start -0.2794 0.1778)
							(mid -0.249642 0.249642)
							(end -0.1778 0.2794)
						)
						(arc
							(start 0.1778 0.2794)
							(mid 0.249642 0.249642)
							(end 0.2794 0.1778)
						)
						(arc
							(start 0.2794 -0.1778)
							(mid 0.249642 -0.249642)
							(end 0.1778 -0.2794)
						)
					)
					(width 0)
					(fill yes)
				)
			)
		)
		(pad "2" smd custom
			(at 0 0.4445 180)
			(size 0.1397 0.1397)
			(layers "F.Cu" "F.Mask" "F.Paste")
			(net "SW_HDD_N24")
			(options
				(clearance outline)
				(anchor circle)
			)
			(primitives
				(gr_poly
					(pts
						(arc
							(start -0.1778 -0.2794)
							(mid -0.249642 -0.249642)
							(end -0.2794 -0.1778)
						)
						(arc
							(start -0.2794 0.1778)
							(mid -0.249642 0.249642)
							(end -0.1778 0.2794)
						)
						(arc
							(start 0.1778 0.2794)
							(mid 0.249642 0.249642)
							(end 0.2794 0.1778)
						)
						(arc
							(start 0.2794 -0.1778)
							(mid 0.249642 -0.249642)
							(end 0.1778 -0.2794)
						)
					)
					(width 0)
					(fill yes)
				)
			)
		)
	)
	(footprint ""
		(layer "F.Cu")
		(at 364.744 -13.589 180)
		(property "Reference" "R791"
			(at 0 0 180)
			(layer "F.SilkS")
			(hide yes)
			(effects
				(font
					(size 1.27 1.27)
				)
			)
		)
		(property "Value" "1KR2F-3-GP"
			(at 0.064008 -3.993896 180)
			(unlocked yes)
			(layer "F.Fab")
			(hide yes)
			(effects
				(font
					(size 1.016 1.016)
					(thickness 0.1524)
				)
			)
		)
		(property "Device Type" "R402H16"
			(at 0.064008 -5.517896 180)
			(unlocked yes)
			(layer "F.Fab")
			(hide yes)
			(effects
				(font
					(size 1.016 1.016)
					(thickness 0.1524)
				)
			)
		)
		(duplicate_pad_numbers_are_jumpers no)
		(fp_line
			(start 0.508 -0.9398)
			(end -0.508 -0.9398)
			(stroke
				(width 0.1524)
				(type default)
			)
			(layer "F.SilkS")
		)
		(fp_line
			(start -0.508 -0.9398)
			(end -0.508 0.9398)
			(stroke
				(width 0.1524)
				(type default)
			)
			(layer "F.SilkS")
		)
		(fp_rect
			(start -0.508 0.9398)
			(end 0.508 -0.9398)
			(stroke
				(width 0)
				(type default)
			)
			(fill no)
			(layer "F.CrtYd")
		)
		(fp_rect
			(start -0.508 0.9398)
			(end 0.508 -0.9398)
			(stroke
				(width 0)
				(type default)
			)
			(fill no)
			(layer "F.Fab")
		)
		(pad "1" smd custom
			(at 0 -0.4445 180)
			(size 0.1397 0.1397)
			(layers "F.Cu" "F.Mask" "F.Paste")
			(net "P3V3_STBY_B")
			(options
				(clearance outline)
				(anchor circle)
			)
			(primitives
				(gr_poly
					(pts
						(arc
							(start -0.1778 -0.2794)
							(mid -0.249642 -0.249642)
							(end -0.2794 -0.1778)
						)
						(arc
							(start -0.2794 0.1778)
							(mid -0.249642 0.249642)
							(end -0.1778 0.2794)
						)
						(arc
							(start 0.1778 0.2794)
							(mid 0.249642 0.249642)
							(end 0.2794 0.1778)
						)
						(arc
							(start 0.2794 -0.1778)
							(mid 0.249642 -0.249642)
							(end 0.1778 -0.2794)
						)
					)
					(width 0)
					(fill yes)
				)
			)
		)
		(pad "2" smd custom
			(at 0 0.4445 180)
			(size 0.1397 0.1397)
			(layers "F.Cu" "F.Mask" "F.Paste")
			(net "SW_PWR_R_HDD31")
			(options
				(clearance outline)
				(anchor circle)
			)
			(primitives
				(gr_poly
					(pts
						(arc
							(start -0.1778 -0.2794)
							(mid -0.249642 -0.249642)
							(end -0.2794 -0.1778)
						)
						(arc
							(start -0.2794 0.1778)
							(mid -0.249642 0.249642)
							(end -0.1778 0.2794)
						)
						(arc
							(start 0.1778 0.2794)
							(mid 0.249642 0.249642)
							(end 0.2794 0.1778)
						)
						(arc
							(start 0.2794 -0.1778)
							(mid 0.249642 -0.249642)
							(end 0.1778 -0.2794)
						)
					)
					(width 0)
					(fill yes)
				)
			)
		)
	)
	(footprint ""
		(layer "F.Cu")
		(at 434.901594 -212.390228 -90)
		(property "Reference" "R309"
			(at 0 0 270)
			(layer "F.SilkS")
			(hide yes)
			(effects
				(font
					(size 1.27 1.27)
				)
			)
		)
		(property "Value" "4K7R2F-GP"
			(at 0.064008 -3.993896 270)
			(unlocked yes)
			(layer "F.Fab")
			(hide yes)
			(effects
				(font
					(size 1.016 1.016)
					(thickness 0.1524)
				)
			)
		)
		(property "Device Type" "R402H16"
			(at 0.064008 -5.517896 270)
			(unlocked yes)
			(layer "F.Fab")
			(hide yes)
			(effects
				(font
					(size 1.016 1.016)
					(thickness 0.1524)
				)
			)
		)
		(duplicate_pad_numbers_are_jumpers no)
		(fp_line
			(start -0.508 -0.9398)
			(end -0.508 0.9398)
			(stroke
				(width 0.1524)
				(type default)
			)
			(layer "F.SilkS")
		)
		(fp_line
			(start 0.508 -0.9398)
			(end -0.508 -0.9398)
			(stroke
				(width 0.1524)
				(type default)
			)
			(layer "F.SilkS")
		)
		(fp_rect
			(start -0.508 0.9398)
			(end 0.508 -0.9398)
			(stroke
				(width 0)
				(type default)
			)
			(fill no)
			(layer "F.CrtYd")
		)
		(fp_rect
			(start -0.508 0.9398)
			(end 0.508 -0.9398)
			(stroke
				(width 0)
				(type default)
			)
			(fill no)
			(layer "F.Fab")
		)
		(pad "1" smd custom
			(at 0 -0.4445 270)
			(size 0.1397 0.1397)
			(layers "F.Cu" "F.Mask" "F.Paste")
			(net "DRIVE_B_10_ACT")
			(options
				(clearance outline)
				(anchor circle)
			)
			(primitives
				(gr_poly
					(pts
						(arc
							(start -0.1778 -0.2794)
							(mid -0.249642 -0.249642)
							(end -0.2794 -0.1778)
						)
						(arc
							(start -0.2794 0.1778)
							(mid -0.249642 0.249642)
							(end -0.1778 0.2794)
						)
						(arc
							(start 0.1778 0.2794)
							(mid 0.249642 0.249642)
							(end 0.2794 0.1778)
						)
						(arc
							(start 0.2794 -0.1778)
							(mid 0.249642 -0.249642)
							(end 0.1778 -0.2794)
						)
					)
					(width 0)
					(fill yes)
				)
			)
		)
		(pad "2" smd custom
			(at 0 0.4445 270)
			(size 0.1397 0.1397)
			(layers "F.Cu" "F.Mask" "F.Paste")
			(net "GND")
			(options
				(clearance outline)
				(anchor circle)
			)
			(primitives
				(gr_poly
					(pts
						(arc
							(start -0.1778 -0.2794)
							(mid -0.249642 -0.249642)
							(end -0.2794 -0.1778)
						)
						(arc
							(start -0.2794 0.1778)
							(mid -0.249642 0.249642)
							(end -0.1778 0.2794)
						)
						(arc
							(start 0.1778 0.2794)
							(mid 0.249642 0.249642)
							(end 0.2794 0.1778)
						)
						(arc
							(start 0.2794 -0.1778)
							(mid 0.249642 -0.249642)
							(end 0.1778 -0.2794)
						)
					)
					(width 0)
					(fill yes)
				)
			)
		)
	)
	(footprint ""
		(layer "F.Cu")
		(at 38.956996 -364.998)
		(property "Reference" "C523"
			(at 0 0 0)
			(layer "F.SilkS")
			(hide yes)
			(effects
				(font
					(size 1.27 1.27)
				)
			)
		)
		(property "Value" "SCD1U25V2KX-2-GP"
			(at 1.1811 -2.7051 0)
			(unlocked yes)
			(layer "F.Fab")
			(hide yes)
			(effects
				(font
					(size 1.016 1.016)
					(thickness 0.1524)
				)
			)
		)
		(property "Device Type" "C402H22"
			(at 1.1811 -4.2291 0)
			(unlocked yes)
			(layer "F.Fab")
			(hide yes)
			(effects
				(font
					(size 1.016 1.016)
					(thickness 0.1524)
				)
			)
		)
		(duplicate_pad_numbers_are_jumpers no)
		(fp_rect
			(start -0.4318 0.9525)
			(end 0.4318 -0.9525)
			(stroke
				(width 0)
				(type default)
			)
			(fill no)
			(layer "F.CrtYd")
		)
		(fp_rect
			(start -0.4318 0.9525)
			(end 0.4318 -0.9525)
			(stroke
				(width 0)
				(type default)
			)
			(fill no)
			(layer "F.Fab")
		)
		(pad "1" smd custom
			(at 0 -0.4445)
			(size 0.1524 0.1524)
			(layers "F.Cu" "F.Mask" "F.Paste")
			(net "FAN_0_TACH1")
			(options
				(clearance outline)
				(anchor circle)
			)
			(primitives
				(gr_poly
					(pts
						(arc
							(start 0.3048 -0.2032)
							(mid 0.275042 -0.275042)
							(end 0.2032 -0.3048)
						)
						(arc
							(start -0.2032 -0.3048)
							(mid -0.275042 -0.275042)
							(end -0.3048 -0.2032)
						)
						(arc
							(start -0.3048 0.2032)
							(mid -0.275042 0.275042)
							(end -0.2032 0.3048)
						)
						(arc
							(start 0.2032 0.3048)
							(mid 0.275042 0.275042)
							(end 0.3048 0.2032)
						)
					)
					(width 0)
					(fill yes)
				)
			)
		)
		(pad "2" smd custom
			(at 0 0.4445)
			(size 0.1524 0.1524)
			(layers "F.Cu" "F.Mask" "F.Paste")
			(net "GND")
			(options
				(clearance outline)
				(anchor circle)
			)
			(primitives
				(gr_poly
					(pts
						(arc
							(start 0.3048 -0.2032)
							(mid 0.275042 -0.275042)
							(end 0.2032 -0.3048)
						)
						(arc
							(start -0.2032 -0.3048)
							(mid -0.275042 -0.275042)
							(end -0.3048 -0.2032)
						)
						(arc
							(start -0.3048 0.2032)
							(mid -0.275042 0.275042)
							(end -0.2032 0.3048)
						)
						(arc
							(start 0.2032 0.3048)
							(mid 0.275042 0.275042)
							(end 0.3048 0.2032)
						)
					)
					(width 0)
					(fill yes)
				)
			)
		)
	)
	(footprint ""
		(layer "F.Cu")
		(at 175.006 -361.696)
		(property "Reference" "R1008"
			(at 0 0 0)
			(layer "F.SilkS")
			(hide yes)
			(effects
				(font
					(size 1.27 1.27)
				)
			)
		)
		(property "Value" "14K3R2F-GP"
			(at 0.064008 -3.993896 0)
			(unlocked yes)
			(layer "F.Fab")
			(hide yes)
			(effects
				(font
					(size 1.016 1.016)
					(thickness 0.1524)
				)
			)
		)
		(property "Device Type" "R402H16"
			(at 0.064008 -5.517896 0)
			(unlocked yes)
			(layer "F.Fab")
			(hide yes)
			(effects
				(font
					(size 1.016 1.016)
					(thickness 0.1524)
				)
			)
		)
		(duplicate_pad_numbers_are_jumpers no)
		(fp_line
			(start -0.508 -0.9398)
			(end -0.508 0.9398)
			(stroke
				(width 0.1524)
				(type default)
			)
			(layer "F.SilkS")
		)
		(fp_line
			(start 0.508 -0.9398)
			(end -0.508 -0.9398)
			(stroke
				(width 0.1524)
				(type default)
			)
			(layer "F.SilkS")
		)
		(fp_rect
			(start -0.508 0.9398)
			(end 0.508 -0.9398)
			(stroke
				(width 0)
				(type default)
			)
			(fill no)
			(layer "F.CrtYd")
		)
		(fp_rect
			(start -0.508 0.9398)
			(end 0.508 -0.9398)
			(stroke
				(width 0)
				(type default)
			)
			(fill no)
			(layer "F.Fab")
		)
		(pad "1" smd custom
			(at 0 -0.4445)
			(size 0.1397 0.1397)
			(layers "F.Cu" "F.Mask" "F.Paste")
			(net "MB0_ISTART_R")
			(options
				(clearance outline)
				(anchor circle)
			)
			(primitives
				(gr_poly
					(pts
						(arc
							(start -0.1778 -0.2794)
							(mid -0.249642 -0.249642)
							(end -0.2794 -0.1778)
						)
						(arc
							(start -0.2794 0.1778)
							(mid -0.249642 0.249642)
							(end -0.1778 0.2794)
						)
						(arc
							(start 0.1778 0.2794)
							(mid 0.249642 0.249642)
							(end 0.2794 0.1778)
						)
						(arc
							(start 0.2794 -0.1778)
							(mid 0.249642 -0.249642)
							(end 0.1778 -0.2794)
						)
					)
					(width 0)
					(fill yes)
				)
			)
		)
		(pad "2" smd custom
			(at 0 0.4445)
			(size 0.1397 0.1397)
			(layers "F.Cu" "F.Mask" "F.Paste")
			(net "AGND_CURRENT_MON")
			(options
				(clearance outline)
				(anchor circle)
			)
			(primitives
				(gr_poly
					(pts
						(arc
							(start -0.1778 -0.2794)
							(mid -0.249642 -0.249642)
							(end -0.2794 -0.1778)
						)
						(arc
							(start -0.2794 0.1778)
							(mid -0.249642 0.249642)
							(end -0.1778 0.2794)
						)
						(arc
							(start 0.1778 0.2794)
							(mid 0.249642 0.249642)
							(end 0.2794 0.1778)
						)
						(arc
							(start 0.2794 -0.1778)
							(mid 0.249642 -0.249642)
							(end 0.1778 -0.2794)
						)
					)
					(width 0)
					(fill yes)
				)
			)
		)
	)
	(footprint ""
		(layer "F.Cu")
		(at 14.859 -30.861)
		(property "Reference" "Q120"
			(at 0 0 0)
			(layer "F.SilkS")
			(hide yes)
			(effects
				(font
					(size 1.27 1.27)
				)
			)
		)
		(property "Value" "AO4407AL-GP"
			(at -3.707384 -1.5367 0)
			(unlocked yes)
			(layer "F.Fab")
			(hide yes)
			(effects
				(font
					(size 1.016 1.016)
					(thickness 0.1524)
				)
			)
		)
		(property "Device Type" "SOIC8H69"
			(at -3.707384 -3.0607 0)
			(unlocked yes)
			(layer "F.Fab")
			(hide yes)
			(effects
				(font
					(size 1.016 1.016)
					(thickness 0.1524)
				)
			)
		)
		(duplicate_pad_numbers_are_jumpers no)
		(fp_line
			(start -2.7432 -1.4224)
			(end -2.7432 1.4224)
			(stroke
				(width 0.1524)
				(type default)
			)
			(layer "F.SilkS")
		)
		(fp_line
			(start -2.7432 1.4224)
			(end -2.6416 1.4224)
			(stroke
				(width 0.1524)
				(type default)
			)
			(layer "F.SilkS")
		)
		(fp_line
			(start -2.7432 1.4224)
			(end 2.1336 1.4224)
			(stroke
				(width 0.1524)
				(type default)
			)
			(layer "F.SilkS")
		)
		(fp_line
			(start -2.7178 -0.508)
			(end -2.1844 -0.0508)
			(stroke
				(width 0.1524)
				(type default)
			)
			(layer "F.SilkS")
		)
		(fp_line
			(start -2.6289 3.4417)
			(end -2.6289 1.4732)
			(stroke
				(width 0.381)
				(type default)
			)
			(layer "F.SilkS")
		)
		(fp_line
			(start -2.1844 -0.0508)
			(end -2.7178 0.508)
			(stroke
				(width 0.1524)
				(type default)
			)
			(layer "F.SilkS")
		)
		(fp_line
			(start 2.1336 -1.4224)
			(end -2.7432 -1.4224)
			(stroke
				(width 0.1524)
				(type default)
			)
			(layer "F.SilkS")
		)
		(fp_line
			(start 2.1336 1.4224)
			(end 2.1336 -1.4224)
			(stroke
				(width 0.1524)
				(type default)
			)
			(layer "F.SilkS")
		)
		(fp_poly
			(pts
				(xy -2.2098 -1.4224) (xy -2.2098 1.4224) (xy 2.2098 1.4224) (xy 2.2098 -1.4224)
			)
			(stroke
				(width 0)
				(type default)
			)
			(fill yes)
			(layer "F.SilkS")
		)
		(fp_rect
			(start -2.450084 2.999994)
			(end 2.450084 -2.999994)
			(stroke
				(width 0)
				(type default)
			)
			(fill no)
			(layer "F.CrtYd")
		)
		(fp_poly
			(pts
				(xy -2.8194 3.6322) (xy -2.8194 -3.6322) (xy 2.8194 -3.6322) (xy 2.8194 1.18364) (xy 2.450084 1.18364)
				(xy 2.450084 -2.999994) (xy -2.450084 -2.999994) (xy -2.450084 2.999994) (xy 2.450084 2.999994)
				(xy 2.450084 1.18618) (xy 2.8194 1.18618) (xy 2.8194 3.6322)
			)
			(stroke
				(width 0)
				(type default)
			)
			(fill no)
			(layer "F.CrtYd")
		)
		(fp_rect
			(start -2.8194 3.6322)
			(end 2.8194 -3.6322)
			(stroke
				(width 0)
				(type default)
			)
			(fill no)
			(layer "F.Fab")
		)
		(pad "1" smd rect
			(at -1.905 2.54)
			(size 0.635 1.651)
			(layers "F.Cu" "F.Mask" "F.Paste")
			(net "P12V_B")
		)
		(pad "2" smd rect
			(at -0.635 2.54)
			(size 0.635 1.651)
			(layers "F.Cu" "F.Mask" "F.Paste")
			(net "P12V_B")
		)
		(pad "3" smd rect
			(at 0.635 2.54)
			(size 0.635 1.651)
			(layers "F.Cu" "F.Mask" "F.Paste")
			(net "P12V_B")
		)
		(pad "4" smd rect
			(at 1.905 2.54)
			(size 0.635 1.651)
			(layers "F.Cu" "F.Mask" "F.Paste")
			(net "SW_HDD_N24")
		)
		(pad "5" smd rect
			(at 1.905 -2.54)
			(size 0.635 1.651)
			(layers "F.Cu" "F.Mask" "F.Paste")
			(net "P12V_HDD24")
		)
		(pad "6" smd rect
			(at 0.635 -2.54)
			(size 0.635 1.651)
			(layers "F.Cu" "F.Mask" "F.Paste")
			(net "P12V_HDD24")
		)
		(pad "7" smd rect
			(at -0.635 -2.54)
			(size 0.635 1.651)
			(layers "F.Cu" "F.Mask" "F.Paste")
			(net "P12V_HDD24")
		)
		(pad "8" smd rect
			(at -1.905 -2.54)
			(size 0.635 1.651)
			(layers "F.Cu" "F.Mask" "F.Paste")
			(net "P12V_HDD24")
		)
	)
	(footprint ""
		(layer "F.Cu")
		(at 469.519 -244.348 180)
		(property "Reference" "R342"
			(at 0 0 180)
			(layer "F.SilkS")
			(hide yes)
			(effects
				(font
					(size 1.27 1.27)
				)
			)
		)
		(property "Value" "0R2J-2-GP"
			(at 0.064008 -3.993896 180)
			(unlocked yes)
			(layer "F.Fab")
			(hide yes)
			(effects
				(font
					(size 1.016 1.016)
					(thickness 0.1524)
				)
			)
		)
		(property "Device Type" "R402H16"
			(at 0.064008 -5.517896 180)
			(unlocked yes)
			(layer "F.Fab")
			(hide yes)
			(effects
				(font
					(size 1.016 1.016)
					(thickness 0.1524)
				)
			)
		)
		(duplicate_pad_numbers_are_jumpers no)
		(fp_line
			(start 0.508 -0.9398)
			(end -0.508 -0.9398)
			(stroke
				(width 0.1524)
				(type default)
			)
			(layer "F.SilkS")
		)
		(fp_line
			(start -0.508 -0.9398)
			(end -0.508 0.9398)
			(stroke
				(width 0.1524)
				(type default)
			)
			(layer "F.SilkS")
		)
		(fp_rect
			(start -0.508 0.9398)
			(end 0.508 -0.9398)
			(stroke
				(width 0)
				(type default)
			)
			(fill no)
			(layer "F.CrtYd")
		)
		(fp_rect
			(start -0.508 0.9398)
			(end 0.508 -0.9398)
			(stroke
				(width 0)
				(type default)
			)
			(fill no)
			(layer "F.Fab")
		)
		(pad "1" smd custom
			(at 0 -0.4445 180)
			(size 0.1397 0.1397)
			(layers "F.Cu" "F.Mask" "F.Paste")
			(net "DRIVE_B_11_PWR")
			(options
				(clearance outline)
				(anchor circle)
			)
			(primitives
				(gr_poly
					(pts
						(arc
							(start -0.1778 -0.2794)
							(mid -0.249642 -0.249642)
							(end -0.2794 -0.1778)
						)
						(arc
							(start -0.2794 0.1778)
							(mid -0.249642 0.249642)
							(end -0.1778 0.2794)
						)
						(arc
							(start 0.1778 0.2794)
							(mid 0.249642 0.249642)
							(end 0.2794 0.1778)
						)
						(arc
							(start 0.2794 -0.1778)
							(mid 0.249642 -0.249642)
							(end 0.1778 -0.2794)
						)
					)
					(width 0)
					(fill yes)
				)
			)
		)
		(pad "2" smd custom
			(at 0 0.4445 180)
			(size 0.1397 0.1397)
			(layers "F.Cu" "F.Mask" "F.Paste")
			(net "SW_PWR_R_HDD11")
			(options
				(clearance outline)
				(anchor circle)
			)
			(primitives
				(gr_poly
					(pts
						(arc
							(start -0.1778 -0.2794)
							(mid -0.249642 -0.249642)
							(end -0.2794 -0.1778)
						)
						(arc
							(start -0.2794 0.1778)
							(mid -0.249642 0.249642)
							(end -0.1778 0.2794)
						)
						(arc
							(start 0.1778 0.2794)
							(mid 0.249642 0.249642)
							(end 0.2794 0.1778)
						)
						(arc
							(start 0.2794 -0.1778)
							(mid 0.249642 -0.249642)
							(end 0.1778 -0.2794)
						)
					)
					(width 0)
					(fill yes)
				)
			)
		)
	)
)
